(kicad_pcb
	(version 20260206)
	(generator "pcbnew")
	(generator_version "10.0")
	(general
		(thickness 1.6)
		(legacy_teardrops no)
	)
	(paper "A4")
	(title_block
		(title "Bryce Canyon_IOM_M2_16342-2_OCP.brd")
		(comment 1 "Bryce Canyon / footprints 663-668 of 1146")
	)
	(layers
		(0 "F.Cu" signal "TOP")
		(4 "In1.Cu" signal "L2GND")
		(6 "In2.Cu" signal "L3")
		(8 "In3.Cu" signal "L4VCC")
		(10 "In4.Cu" signal "L5VCC")
		(12 "In5.Cu" signal "L6")
		(14 "In6.Cu" signal "L7GND")
		(2 "B.Cu" signal "BOTTOM")
		(9 "F.Adhes" user "F.Adhesive")
		(11 "B.Adhes" user "B.Adhesive")
		(13 "F.Paste" user "Package Geometry/Pastemask Top")
		(15 "B.Paste" user "Package Geometry/Pastemask Bottom")
		(5 "F.SilkS" user "Ref Des/Silkscreen Top")
		(7 "B.SilkS" user "Ref Des/Silkscreen Bottom")
		(1 "F.Mask" user "Board Geometry/Soldermask Top")
		(3 "B.Mask" user "Board Geometry/Soldermask Bottom")
		(17 "Dwgs.User" user "User.Drawings")
		(19 "Cmts.User" user "User.Comments")
		(21 "Eco1.User" user "User.Eco1")
		(23 "Eco2.User" user "User.Eco2")
		(25 "Edge.Cuts" user "Board Geometry/Outline")
		(27 "Margin" user)
		(31 "F.CrtYd" user "Package Geometry/Place Bound Top")
		(29 "B.CrtYd" user "Package Geometry/Place Bound Bottom")
		(35 "F.Fab" user "Ref Des/Assembly Top")
		(33 "B.Fab" user "Ref Des/Assembly Bottom")
	)
	(footprint ""
		(layer "F.Cu")
		(at 22.014942 -129.1082 180)
		(property "Reference" "R213"
			(at 0 0 180)
			(layer "F.SilkS")
			(hide yes)
			(effects
				(font
					(size 1.27 1.27)
				)
			)
		)
		(property "Value" "120R2F-GP"
			(at 0.064008 -3.993896 180)
			(unlocked yes)
			(layer "F.Fab")
			(hide yes)
			(effects
				(font
					(size 1.016 1.016)
					(thickness 0.1524)
				)
			)
		)
		(property "Device Type" "R402H16"
			(at 0.064008 -5.517896 180)
			(unlocked yes)
			(layer "F.Fab")
			(hide yes)
			(effects
				(font
					(size 1.016 1.016)
					(thickness 0.1524)
				)
			)
		)
		(duplicate_pad_numbers_are_jumpers no)
		(fp_line
			(start 0.508 -0.9398)
			(end -0.508 -0.9398)
			(stroke
				(width 0.1524)
				(type default)
			)
			(layer "F.SilkS")
		)
		(fp_line
			(start -0.508 -0.9398)
			(end -0.508 0.9398)
			(stroke
				(width 0.1524)
				(type default)
			)
			(layer "F.SilkS")
		)
		(fp_rect
			(start -0.508 0.9398)
			(end 0.508 -0.9398)
			(stroke
				(width 0)
				(type default)
			)
			(fill no)
			(layer "F.CrtYd")
		)
		(fp_rect
			(start -0.508 0.9398)
			(end 0.508 -0.9398)
			(stroke
				(width 0)
				(type default)
			)
			(fill no)
			(layer "F.Fab")
		)
		(pad "1" smd custom
			(at 0 -0.4445 180)
			(size 0.1397 0.1397)
			(layers "F.Cu" "F.Mask" "F.Paste")
			(net "GND")
			(options
				(clearance outline)
				(anchor circle)
			)
			(primitives
				(gr_poly
					(pts
						(arc
							(start -0.1778 -0.2794)
							(mid -0.249642 -0.249642)
							(end -0.2794 -0.1778)
						)
						(arc
							(start -0.2794 0.1778)
							(mid -0.249642 0.249642)
							(end -0.1778 0.2794)
						)
						(arc
							(start 0.1778 0.2794)
							(mid 0.249642 0.249642)
							(end 0.2794 0.1778)
						)
						(arc
							(start 0.2794 -0.1778)
							(mid 0.249642 -0.249642)
							(end 0.1778 -0.2794)
						)
					)
					(width 0)
					(fill yes)
				)
			)
		)
		(pad "2" smd custom
			(at 0 0.4445 180)
			(size 0.1397 0.1397)
			(layers "F.Cu" "F.Mask" "F.Paste")
			(net "DDR4_ALERT")
			(options
				(clearance outline)
				(anchor circle)
			)
			(primitives
				(gr_poly
					(pts
						(arc
							(start -0.1778 -0.2794)
							(mid -0.249642 -0.249642)
							(end -0.2794 -0.1778)
						)
						(arc
							(start -0.2794 0.1778)
							(mid -0.249642 0.249642)
							(end -0.1778 0.2794)
						)
						(arc
							(start 0.1778 0.2794)
							(mid 0.249642 0.249642)
							(end 0.2794 0.1778)
						)
						(arc
							(start 0.2794 -0.1778)
							(mid 0.249642 -0.249642)
							(end 0.1778 -0.2794)
						)
					)
					(width 0)
					(fill yes)
				)
			)
		)
	)
	(footprint ""
		(layer "F.Cu")
		(at 72.22998 -164.586412 90)
		(property "Reference" "R541"
			(at 0 0 90)
			(layer "F.SilkS")
			(hide yes)
			(effects
				(font
					(size 1.27 1.27)
				)
			)
		)
		(property "Value" "4K75R2F-1-GP"
			(at 0.064008 -3.993896 90)
			(unlocked yes)
			(layer "F.Fab")
			(hide yes)
			(effects
				(font
					(size 1.016 1.016)
					(thickness 0.1524)
				)
			)
		)
		(property "Device Type" "R402H16"
			(at 0.064008 -5.517896 90)
			(unlocked yes)
			(layer "F.Fab")
			(hide yes)
			(effects
				(font
					(size 1.016 1.016)
					(thickness 0.1524)
				)
			)
		)
		(duplicate_pad_numbers_are_jumpers no)
		(fp_line
			(start 0.508 -0.9398)
			(end -0.508 -0.9398)
			(stroke
				(width 0.1524)
				(type default)
			)
			(layer "F.SilkS")
		)
		(fp_line
			(start -0.508 -0.9398)
			(end -0.508 0.9398)
			(stroke
				(width 0.1524)
				(type default)
			)
			(layer "F.SilkS")
		)
		(fp_rect
			(start -0.508 0.9398)
			(end 0.508 -0.9398)
			(stroke
				(width 0)
				(type default)
			)
			(fill no)
			(layer "F.CrtYd")
		)
		(fp_rect
			(start -0.508 0.9398)
			(end 0.508 -0.9398)
			(stroke
				(width 0)
				(type default)
			)
			(fill no)
			(layer "F.Fab")
		)
		(pad "1" smd custom
			(at 0 -0.4445 90)
			(size 0.1397 0.1397)
			(layers "F.Cu" "F.Mask" "F.Paste")
			(net "P3V3_STBY")
			(options
				(clearance outline)
				(anchor circle)
			)
			(primitives
				(gr_poly
					(pts
						(arc
							(start -0.1778 -0.2794)
							(mid -0.249642 -0.249642)
							(end -0.2794 -0.1778)
						)
						(arc
							(start -0.2794 0.1778)
							(mid -0.249642 0.249642)
							(end -0.1778 0.2794)
						)
						(arc
							(start 0.1778 0.2794)
							(mid 0.249642 0.249642)
							(end 0.2794 0.1778)
						)
						(arc
							(start 0.2794 -0.1778)
							(mid 0.249642 -0.249642)
							(end 0.1778 -0.2794)
						)
					)
					(width 0)
					(fill yes)
				)
			)
		)
		(pad "2" smd custom
			(at 0 0.4445 90)
			(size 0.1397 0.1397)
			(layers "F.Cu" "F.Mask" "F.Paste")
			(net "TPS74801_P1V15_STBY_EN")
			(options
				(clearance outline)
				(anchor circle)
			)
			(primitives
				(gr_poly
					(pts
						(arc
							(start -0.1778 -0.2794)
							(mid -0.249642 -0.249642)
							(end -0.2794 -0.1778)
						)
						(arc
							(start -0.2794 0.1778)
							(mid -0.249642 0.249642)
							(end -0.1778 0.2794)
						)
						(arc
							(start 0.1778 0.2794)
							(mid 0.249642 0.249642)
							(end 0.2794 0.1778)
						)
						(arc
							(start 0.2794 -0.1778)
							(mid 0.249642 -0.249642)
							(end 0.1778 -0.2794)
						)
					)
					(width 0)
					(fill yes)
				)
			)
		)
	)
	(footprint ""
		(layer "F.Cu")
		(at 39.1922 -179.12461)
		(property "Reference" "R491"
			(at 0 0 0)
			(layer "F.SilkS")
			(hide yes)
			(effects
				(font
					(size 1.27 1.27)
				)
			)
		)
		(property "Value" "15KR2F-GP"
			(at 0.064008 -3.993896 0)
			(unlocked yes)
			(layer "F.Fab")
			(hide yes)
			(effects
				(font
					(size 1.016 1.016)
					(thickness 0.1524)
				)
			)
		)
		(property "Device Type" "R402H16"
			(at 0.064008 -5.517896 0)
			(unlocked yes)
			(layer "F.Fab")
			(hide yes)
			(effects
				(font
					(size 1.016 1.016)
					(thickness 0.1524)
				)
			)
		)
		(duplicate_pad_numbers_are_jumpers no)
		(fp_line
			(start -0.508 -0.9398)
			(end -0.508 0.9398)
			(stroke
				(width 0.1524)
				(type default)
			)
			(layer "F.SilkS")
		)
		(fp_line
			(start 0.508 -0.9398)
			(end -0.508 -0.9398)
			(stroke
				(width 0.1524)
				(type default)
			)
			(layer "F.SilkS")
		)
		(fp_rect
			(start -0.508 0.9398)
			(end 0.508 -0.9398)
			(stroke
				(width 0)
				(type default)
			)
			(fill no)
			(layer "F.CrtYd")
		)
		(fp_rect
			(start -0.508 0.9398)
			(end 0.508 -0.9398)
			(stroke
				(width 0)
				(type default)
			)
			(fill no)
			(layer "F.Fab")
		)
		(pad "1" smd custom
			(at 0 -0.4445)
			(size 0.1397 0.1397)
			(layers "F.Cu" "F.Mask" "F.Paste")
			(net "PWRGD_P3V3_STBY")
			(options
				(clearance outline)
				(anchor circle)
			)
			(primitives
				(gr_poly
					(pts
						(arc
							(start -0.1778 -0.2794)
							(mid -0.249642 -0.249642)
							(end -0.2794 -0.1778)
						)
						(arc
							(start -0.2794 0.1778)
							(mid -0.249642 0.249642)
							(end -0.1778 0.2794)
						)
						(arc
							(start 0.1778 0.2794)
							(mid 0.249642 0.249642)
							(end 0.2794 0.1778)
						)
						(arc
							(start 0.2794 -0.1778)
							(mid 0.249642 -0.249642)
							(end 0.1778 -0.2794)
						)
					)
					(width 0)
					(fill yes)
				)
			)
		)
		(pad "2" smd custom
			(at 0 0.4445)
			(size 0.1397 0.1397)
			(layers "F.Cu" "F.Mask" "F.Paste")
			(net "GND")
			(options
				(clearance outline)
				(anchor circle)
			)
			(primitives
				(gr_poly
					(pts
						(arc
							(start -0.1778 -0.2794)
							(mid -0.249642 -0.249642)
							(end -0.2794 -0.1778)
						)
						(arc
							(start -0.2794 0.1778)
							(mid -0.249642 0.249642)
							(end -0.1778 0.2794)
						)
						(arc
							(start 0.1778 0.2794)
							(mid 0.249642 0.249642)
							(end 0.2794 0.1778)
						)
						(arc
							(start 0.2794 -0.1778)
							(mid 0.249642 -0.249642)
							(end 0.1778 -0.2794)
						)
					)
					(width 0)
					(fill yes)
				)
			)
		)
	)
	(footprint ""
		(layer "F.Cu")
		(at 41.719246 -177.14341)
		(property "Reference" "R485"
			(at 0 0 0)
			(layer "F.SilkS")
			(hide yes)
			(effects
				(font
					(size 1.27 1.27)
				)
			)
		)
		(property "Value" "0R2J-2-GP"
			(at 0.064008 -3.993896 0)
			(unlocked yes)
			(layer "F.Fab")
			(hide yes)
			(effects
				(font
					(size 1.016 1.016)
					(thickness 0.1524)
				)
			)
		)
		(property "Device Type" "R402H16"
			(at 0.064008 -5.517896 0)
			(unlocked yes)
			(layer "F.Fab")
			(hide yes)
			(effects
				(font
					(size 1.016 1.016)
					(thickness 0.1524)
				)
			)
		)
		(duplicate_pad_numbers_are_jumpers no)
		(fp_line
			(start -0.508 -0.9398)
			(end -0.508 0.9398)
			(stroke
				(width 0.1524)
				(type default)
			)
			(layer "F.SilkS")
		)
		(fp_line
			(start 0.508 -0.9398)
			(end -0.508 -0.9398)
			(stroke
				(width 0.1524)
				(type default)
			)
			(layer "F.SilkS")
		)
		(fp_rect
			(start -0.508 0.9398)
			(end 0.508 -0.9398)
			(stroke
				(width 0)
				(type default)
			)
			(fill no)
			(layer "F.CrtYd")
		)
		(fp_rect
			(start -0.508 0.9398)
			(end 0.508 -0.9398)
			(stroke
				(width 0)
				(type default)
			)
			(fill no)
			(layer "F.Fab")
		)
		(pad "1" smd custom
			(at 0 -0.4445)
			(size 0.1397 0.1397)
			(layers "F.Cu" "F.Mask" "F.Paste")
			(net "P3V3_STBY_EN")
			(options
				(clearance outline)
				(anchor circle)
			)
			(primitives
				(gr_poly
					(pts
						(arc
							(start -0.1778 -0.2794)
							(mid -0.249642 -0.249642)
							(end -0.2794 -0.1778)
						)
						(arc
							(start -0.2794 0.1778)
							(mid -0.249642 0.249642)
							(end -0.1778 0.2794)
						)
						(arc
							(start 0.1778 0.2794)
							(mid 0.249642 0.249642)
							(end 0.2794 0.1778)
						)
						(arc
							(start 0.2794 -0.1778)
							(mid 0.249642 -0.249642)
							(end 0.1778 -0.2794)
						)
					)
					(width 0)
					(fill yes)
				)
			)
		)
		(pad "2" smd custom
			(at 0 0.4445)
			(size 0.1397 0.1397)
			(layers "F.Cu" "F.Mask" "F.Paste")
			(net "PWRGD_P5V_STBY")
			(options
				(clearance outline)
				(anchor circle)
			)
			(primitives
				(gr_poly
					(pts
						(arc
							(start -0.1778 -0.2794)
							(mid -0.249642 -0.249642)
							(end -0.2794 -0.1778)
						)
						(arc
							(start -0.2794 0.1778)
							(mid -0.249642 0.249642)
							(end -0.1778 0.2794)
						)
						(arc
							(start 0.1778 0.2794)
							(mid 0.249642 0.249642)
							(end 0.2794 0.1778)
						)
						(arc
							(start 0.2794 -0.1778)
							(mid 0.249642 -0.249642)
							(end 0.1778 -0.2794)
						)
					)
					(width 0)
					(fill yes)
				)
			)
		)
	)
	(footprint ""
		(layer "F.Cu")
		(at 84.983828 -91.750896 90)
		(property "Reference" "VIA15"
			(at 0 0 90)
			(layer "F.SilkS")
			(hide yes)
			(effects
				(font
					(size 1.27 1.27)
				)
			)
		)
		(property "Value" "85OHM-8L-1D6MM-L16L18-GP"
			(at 4.064 0.6096 90)
			(unlocked yes)
			(layer "F.Fab")
			(hide yes)
			(effects
				(font
					(size 1.016 1.016)
					(thickness 0.1524)
				)
			)
		)
		(property "Device Type" "VIA-PCIE-4P-368076"
			(at 4.064 -0.9144 90)
			(unlocked yes)
			(layer "F.Fab")
			(hide yes)
			(effects
				(font
					(size 1.016 1.016)
					(thickness 0.1524)
				)
			)
		)
		(duplicate_pad_numbers_are_jumpers no)
		(fp_rect
			(start -1.8415 0.381)
			(end 1.8415 -0.381)
			(stroke
				(width 0)
				(type default)
			)
			(fill no)
			(layer "F.CrtYd")
		)
		(fp_rect
			(start -1.8415 0.381)
			(end 1.8415 -0.381)
			(stroke
				(width 0)
				(type default)
			)
			(fill no)
			(layer "F.Fab")
		)
		(pad "1" thru_hole circle
			(at -1.4605 0 90)
			(size 0.508 0.508)
			(drill 0.254)
			(layers "*.Cu" "*.Mask")
			(remove_unused_layers no)
			(net "GND")
			(clearance 0.127)
			(thermal_gap 0.127)
		)
		(pad "2" thru_hole circle
			(at -0.4445 0 90)
			(size 0.508 0.508)
			(drill 0.254)
			(layers "*.Cu" "*.Mask")
			(remove_unused_layers no)
			(net "PCIE_IOM_TO_COMP_22_DP")
			(clearance 0.127)
			(thermal_gap 0.127)
		)
		(pad "3" thru_hole circle
			(at 0.4445 0 90)
			(size 0.508 0.508)
			(drill 0.254)
			(layers "*.Cu" "*.Mask")
			(remove_unused_layers no)
			(net "PCIE_IOM_TO_COMP_22_DN")
			(clearance 0.127)
			(thermal_gap 0.127)
		)
		(pad "4" thru_hole circle
			(at 1.4605 0 90)
			(size 0.508 0.508)
			(drill 0.254)
			(layers "*.Cu" "*.Mask")
			(remove_unused_layers no)
			(net "GND")
			(clearance 0.127)
			(thermal_gap 0.127)
		)
	)
	(footprint ""
		(layer "F.Cu")
		(at 36.046156 -132.470652)
		(property "Reference" "R312"
			(at 0 0 0)
			(layer "F.SilkS")
			(hide yes)
			(effects
				(font
					(size 1.27 1.27)
				)
			)
		)
		(property "Value" "0R2J-2-GP"
			(at 0.064008 -3.993896 0)
			(unlocked yes)
			(layer "F.Fab")
			(hide yes)
			(effects
				(font
					(size 1.016 1.016)
					(thickness 0.1524)
				)
			)
		)
		(property "Device Type" "R402H16"
			(at 0.064008 -5.517896 0)
			(unlocked yes)
			(layer "F.Fab")
			(hide yes)
			(effects
				(font
					(size 1.016 1.016)
					(thickness 0.1524)
				)
			)
		)
		(duplicate_pad_numbers_are_jumpers no)
		(fp_line
			(start -0.508 -0.9398)
			(end -0.508 0.9398)
			(stroke
				(width 0.1524)
				(type default)
			)
			(layer "F.SilkS")
		)
		(fp_line
			(start 0.508 -0.9398)
			(end -0.508 -0.9398)
			(stroke
				(width 0.1524)
				(type default)
			)
			(layer "F.SilkS")
		)
		(fp_rect
			(start -0.508 0.9398)
			(end 0.508 -0.9398)
			(stroke
				(width 0)
				(type default)
			)
			(fill no)
			(layer "F.CrtYd")
		)
		(fp_rect
			(start -0.508 0.9398)
			(end 0.508 -0.9398)
			(stroke
				(width 0)
				(type default)
			)
			(fill no)
			(layer "F.Fab")
		)
		(pad "1" smd custom
			(at 0 -0.4445)
			(size 0.1397 0.1397)
			(layers "F.Cu" "F.Mask" "F.Paste")
			(net "CLKIN_24M_BMC")
			(options
				(clearance outline)
				(anchor circle)
			)
			(primitives
				(gr_poly
					(pts
						(arc
							(start -0.1778 -0.2794)
							(mid -0.249642 -0.249642)
							(end -0.2794 -0.1778)
						)
						(arc
							(start -0.2794 0.1778)
							(mid -0.249642 0.249642)
							(end -0.1778 0.2794)
						)
						(arc
							(start 0.1778 0.2794)
							(mid 0.249642 0.249642)
							(end 0.2794 0.1778)
						)
						(arc
							(start 0.2794 -0.1778)
							(mid 0.249642 -0.249642)
							(end 0.1778 -0.2794)
						)
					)
					(width 0)
					(fill yes)
				)
			)
		)
		(pad "2" smd custom
			(at 0 0.4445)
			(size 0.1397 0.1397)
			(layers "F.Cu" "F.Mask" "F.Paste")
			(net "OSC_OUT")
			(options
				(clearance outline)
				(anchor circle)
			)
			(primitives
				(gr_poly
					(pts
						(arc
							(start -0.1778 -0.2794)
							(mid -0.249642 -0.249642)
							(end -0.2794 -0.1778)
						)
						(arc
							(start -0.2794 0.1778)
							(mid -0.249642 0.249642)
							(end -0.1778 0.2794)
						)
						(arc
							(start 0.1778 0.2794)
							(mid 0.249642 0.249642)
							(end 0.2794 0.1778)
						)
						(arc
							(start 0.2794 -0.1778)
							(mid 0.249642 -0.249642)
							(end 0.1778 -0.2794)
						)
					)
					(width 0)
					(fill yes)
				)
			)
		)
	)
)
